# T6G (Grand Teton) — schematic netlist excerpt (pin names and nets, part order shuffled) for the footprints in the layout excerpt that follows; sources: Cadence DE-HDL packaged netlist, KiCad conversion of 04192023_DAF0TMB3IC0_F0TG_MB_C_brd_V02_OCP.brd

R3865  Q_RES  0 5% CHIP  pkg 0402LF  page 257 : A = P12V_OCP_SFF_ISENSE_MAM_TIC ; B = P12V_OCP_SFF_ISENSE_TIC
PC561  Q_CAP  0.22UF 16V 10% X7R  pkg 0402  page 195 : A = SW_PVDDCR_CPU0_P0_BOOT4_RC ; B = SW_PVDDCR_CPU0_P0_PH4

(kicad_pcb
	(version 20260206)
	(generator "pcbnew")
	(generator_version "10.0")
	(general
		(thickness 1.6)
		(legacy_teardrops no)
	)
	(paper "A4")
	(title_block
		(title "04192023_DAF0TMB3IC0_F0TG_MB_C_brd_V02_OCP.brd")
		(comment 1 "Grand Teton / footprints 1644-1645 of 8354")
	)
	(layers
		(0 "F.Cu" signal "TOP")
		(4 "In1.Cu" signal "GND")
		(6 "In2.Cu" signal "IN1")
		(8 "In3.Cu" signal "GND1")
		(10 "In4.Cu" signal "IN2")
		(12 "In5.Cu" signal "GND2")
		(14 "In6.Cu" signal "IN3")
		(16 "In7.Cu" signal "GND3")
		(18 "In8.Cu" signal "VCC")
		(20 "In9.Cu" signal "VCC1")
		(22 "In10.Cu" signal "GND4")
		(24 "In11.Cu" signal "IN4")
		(26 "In12.Cu" signal "GND5")
		(28 "In13.Cu" signal "IN5")
		(30 "In14.Cu" signal "GND6")
		(32 "In15.Cu" signal "IN6")
		(34 "In16.Cu" signal "GND7")
		(2 "B.Cu" signal "BOTTOM")
		(9 "F.Adhes" user "F.Adhesive")
		(11 "B.Adhes" user "B.Adhesive")
		(13 "F.Paste" user "Package Geometry/Pastemask Top")
		(15 "B.Paste" user "Package Geometry/Pastemask Bottom")
		(5 "F.SilkS" user "Ref Des/Silkscreen Top")
		(7 "B.SilkS" user "Ref Des/Silkscreen Bottom")
		(1 "F.Mask" user "Board Geometry/Soldermask Top")
		(3 "B.Mask" user "Board Geometry/Soldermask Bottom")
		(17 "Dwgs.User" user "User.Drawings")
		(19 "Cmts.User" user "User.Comments")
		(21 "Eco1.User" user "User.Eco1")
		(23 "Eco2.User" user "User.Eco2")
		(25 "Edge.Cuts" user "Board Geometry/Outline")
		(27 "Margin" user)
		(31 "F.CrtYd" user "Package Geometry/Place Bound Top")
		(29 "B.CrtYd" user "Package Geometry/Place Bound Bottom")
		(35 "F.Fab" user "Ref Des/Assembly Top")
		(33 "B.Fab" user "Ref Des/Assembly Bottom")
	)
	(footprint ""
		(layer "F.Cu")
		(at 323.637148 -45.86351 180)
		(property "Reference" "R3865"
			(at 0 0 180)
			(layer "F.SilkS")
			(hide yes)
			(effects
				(font
					(size 1.27 1.27)
				)
			)
		)
		(property "Value" ""
			(at 0 0 180)
			(layer "F.Fab")
			(effects
				(font
					(size 1.27 1.27)
				)
			)
		)
		(duplicate_pad_numbers_are_jumpers no)
		(fp_line
			(start 0.7874 0.4064)
			(end -0.7874 0.4064)
			(stroke
				(width 0.1524)
				(type default)
			)
			(layer "F.SilkS")
		)
		(fp_line
			(start 0.7874 -0.4064)
			(end 0.7874 0.4064)
			(stroke
				(width 0.1524)
				(type default)
			)
			(layer "F.SilkS")
		)
		(fp_line
			(start -0.7874 0.4064)
			(end -0.7874 -0.4064)
			(stroke
				(width 0.1524)
				(type default)
			)
			(layer "F.SilkS")
		)
		(fp_line
			(start -0.7874 -0.4064)
			(end 0.7874 -0.4064)
			(stroke
				(width 0.1524)
				(type default)
			)
			(layer "F.SilkS")
		)
		(fp_line
			(start 0.67945 0.3048)
			(end 0.120396 0.3048)
			(stroke
				(width 0.1)
				(type default)
			)
			(layer "F.Fab")
		)
		(fp_line
			(start 0.67945 -0.3048)
			(end 0.67945 0.3048)
			(stroke
				(width 0.1)
				(type default)
			)
			(layer "F.Fab")
		)
		(fp_line
			(start 0.12065 -0.2794)
			(end 0.12065 -0.3048)
			(stroke
				(width 0.1)
				(type default)
			)
			(layer "F.Fab")
		)
		(fp_line
			(start 0.12065 -0.3048)
			(end 0.67945 -0.3048)
			(stroke
				(width 0.1)
				(type default)
			)
			(layer "F.Fab")
		)
		(fp_line
			(start 0.120396 0.3048)
			(end 0.120396 0.2794)
			(stroke
				(width 0.1)
				(type default)
			)
			(layer "F.Fab")
		)
		(fp_line
			(start 0.120396 0.2794)
			(end -0.12065 0.2794)
			(stroke
				(width 0.1)
				(type default)
			)
			(layer "F.Fab")
		)
		(fp_line
			(start -0.12065 0.3048)
			(end -0.67945 0.3048)
			(stroke
				(width 0.1)
				(type default)
			)
			(layer "F.Fab")
		)
		(fp_line
			(start -0.12065 0.2794)
			(end -0.12065 0.3048)
			(stroke
				(width 0.1)
				(type default)
			)
			(layer "F.Fab")
		)
		(fp_line
			(start -0.12065 -0.2794)
			(end 0.12065 -0.2794)
			(stroke
				(width 0.1)
				(type default)
			)
			(layer "F.Fab")
		)
		(fp_line
			(start -0.12065 -0.305054)
			(end -0.12065 -0.2794)
			(stroke
				(width 0.1)
				(type default)
			)
			(layer "F.Fab")
		)
		(fp_line
			(start -0.67945 0.3048)
			(end -0.67945 -0.305054)
			(stroke
				(width 0.1)
				(type default)
			)
			(layer "F.Fab")
		)
		(fp_line
			(start -0.67945 -0.305054)
			(end -0.12065 -0.305054)
			(stroke
				(width 0.1)
				(type default)
			)
			(layer "F.Fab")
		)
		(pad "1" smd rect
			(at -0.40005 0)
			(size 0.4572 0.508)
			(layers "F.Cu" "F.Mask" "F.Paste")
			(net "P12V_OCP_SFF_ISENSE_MAM_TIC")
		)
		(pad "2" smd rect
			(at 0.40005 0)
			(size 0.4572 0.508)
			(layers "F.Cu" "F.Mask" "F.Paste")
			(net "P12V_OCP_SFF_ISENSE_TIC")
		)
	)
	(footprint ""
		(layer "F.Cu")
		(at 387.623304 -178.0921 90)
		(property "Reference" "PC561"
			(at 0 0 90)
			(layer "F.SilkS")
			(hide yes)
			(effects
				(font
					(size 1.27 1.27)
				)
			)
		)
		(property "Value" ""
			(at 0 0 90)
			(layer "F.Fab")
			(effects
				(font
					(size 1.27 1.27)
				)
			)
		)
		(duplicate_pad_numbers_are_jumpers no)
		(fp_line
			(start 0.7874 -0.4064)
			(end 0.7874 0.4064)
			(stroke
				(width 0.1524)
				(type default)
			)
			(layer "F.SilkS")
		)
		(fp_line
			(start -0.7874 -0.4064)
			(end 0.7874 -0.4064)
			(stroke
				(width 0.1524)
				(type default)
			)
			(layer "F.SilkS")
		)
		(fp_line
			(start 0.7874 0.4064)
			(end -0.7874 0.4064)
			(stroke
				(width 0.1524)
				(type default)
			)
			(layer "F.SilkS")
		)
		(fp_line
			(start -0.7874 0.4064)
			(end -0.7874 -0.4064)
			(stroke
				(width 0.1524)
				(type default)
			)
			(layer "F.SilkS")
		)
		(fp_line
			(start -0.12065 -0.305054)
			(end -0.12065 -0.2794)
			(stroke
				(width 0.1)
				(type default)
			)
			(layer "F.Fab")
		)
		(fp_line
			(start -0.67945 -0.305054)
			(end -0.12065 -0.305054)
			(stroke
				(width 0.1)
				(type default)
			)
			(layer "F.Fab")
		)
		(fp_line
			(start 0.67945 -0.3048)
			(end 0.67945 0.3048)
			(stroke
				(width 0.1)
				(type default)
			)
			(layer "F.Fab")
		)
		(fp_line
			(start 0.12065 -0.3048)
			(end 0.67945 -0.3048)
			(stroke
				(width 0.1)
				(type default)
			)
			(layer "F.Fab")
		)
		(fp_line
			(start 0.12065 -0.2794)
			(end 0.12065 -0.3048)
			(stroke
				(width 0.1)
				(type default)
			)
			(layer "F.Fab")
		)
		(fp_line
			(start -0.12065 -0.2794)
			(end 0.12065 -0.2794)
			(stroke
				(width 0.1)
				(type default)
			)
			(layer "F.Fab")
		)
		(fp_line
			(start 0.120396 0.2794)
			(end -0.12065 0.2794)
			(stroke
				(width 0.1)
				(type default)
			)
			(layer "F.Fab")
		)
		(fp_line
			(start -0.12065 0.2794)
			(end -0.12065 0.3048)
			(stroke
				(width 0.1)
				(type default)
			)
			(layer "F.Fab")
		)
		(fp_line
			(start 0.67945 0.3048)
			(end 0.120396 0.3048)
			(stroke
				(width 0.1)
				(type default)
			)
			(layer "F.Fab")
		)
		(fp_line
			(start 0.120396 0.3048)
			(end 0.120396 0.2794)
			(stroke
				(width 0.1)
				(type default)
			)
			(layer "F.Fab")
		)
		(fp_line
			(start -0.12065 0.3048)
			(end -0.67945 0.3048)
			(stroke
				(width 0.1)
				(type default)
			)
			(layer "F.Fab")
		)
		(fp_line
			(start -0.67945 0.3048)
			(end -0.67945 -0.305054)
			(stroke
				(width 0.1)
				(type default)
			)
			(layer "F.Fab")
		)
		(pad "1" smd circle
			(at -0.40005 0 90)
			(size 0 0)
			(layers "F.Cu" "F.Mask" "F.Paste")
			(net "SW_PVDDCR_CPU0_P0_BOOT4_RC")
		)
		(pad "2" smd circle
			(at 0.40005 0 90)
			(size 0 0)
			(layers "F.Cu" "F.Mask" "F.Paste")
			(net "SW_PVDDCR_CPU0_P0_PH4")
		)
	)
)
